FILE_TYPE=LIBRARY_PARTS;
primitive 'SLG55021','SLG55021_DFN','SLG55021_SM';
  pin
    'GND':
      PIN_NUMBER='(4)';
      PINUSE='GROUND';
      NO_LOAD_CHECK='Both';
      NO_IO_CHECK='Both';
      NO_ASSERT_CHECK='TRUE';
      NO_DIR_CHECK='TRUE';
      ALLOW_CONNECT='TRUE';
    'THPAD':
      PIN_NUMBER='(9)';
      PINUSE='GROUND';
      NO_LOAD_CHECK='Both';
      NO_IO_CHECK='Both';
      NO_ASSERT_CHECK='TRUE';
      NO_DIR_CHECK='TRUE';
      ALLOW_CONNECT='TRUE';
    'VCC':
      PIN_NUMBER='(1)';
      PINUSE='POWER';
      NO_LOAD_CHECK='Both';
      NO_IO_CHECK='Both';
      NO_ASSERT_CHECK='TRUE';
      NO_DIR_CHECK='TRUE';
      ALLOW_CONNECT='TRUE';
    'ON':
      PIN_NUMBER='(2)';
      INPUT_LOAD='(-0.01,0.01)';
    'SHDN_N':
      PIN_NUMBER='(3)';
      INPUT_LOAD='(-0.01,0.01)';
    'D':
      PIN_NUMBER='(5)';
      INPUT_LOAD='(-0.01,0.01)';
    'S':
      PIN_NUMBER='(6)';
      INPUT_LOAD='(-0.01,0.01)';
    'G':
      PIN_NUMBER='(7)';
      OUTPUT_LOAD='(1.0,-1.0)';
    'PG':
      PIN_NUMBER='(8)';
      OUTPUT_LOAD='(1.0,-1.0)';
  end_pin;
  body
    PART_NAME='SLG55021';
    PHYS_DES_PREFIX='EU';
  end_body;
end_primitive;

END.
